FILE_TYPE = MACRO_DRAWING;
SET COLOR_WIRE YELLOW;
SET COLOR_PROP ORANGE;
SET COLOR_DOT WHITE;
SET COLOR_ARC YELLOW;
SET COLOR_BODY GREEN;
SET COLOR_NOTE PURPLE;
SET PROP_DISPLAY VALUE;
SET PAGE_NUMBER P48;
FORCEADD SOCKET4677_AZIF0045P001C01CS..5
(550 3125);
FORCEPROP 1 LAST PART_NUMBER DGA^7000023
J 0
(-500 4275);
DISPLAY 0.723404 (-500 4275);
PAINT GREEN (-500 4275);
DISPLAY INVISIBLE (-500 4275);
FORCEPROP 2 LAST PART_TYPE SMLF
J 0
(-500 4450);
DISPLAY 1.021277 (-500 4450);
FORCEPROP 1 LAST MATERIAL IO
J 0
(-500 4200);
DISPLAY 0.723404 (-500 4200);
PAINT GREEN (-500 4200);
FORCEPROP 2 LAST VALUE SOCKET4677_AZIF0045-P001C01CS
J 0
(-500 4400);
DISPLAY 1.021277 (-500 4400);
FORCEPROP 1 LAST $LOCATION U1
J 0
(-500 4350);
DISPLAY 0.723404 (-500 4350);
PAINT GREEN (-500 4350);
FORCEPROP 0 LASTPIN (-650 3200) $PN AC78
J 2
(-660 3210);
DISPLAY 0.680851 (-660 3210);
PAINT MONO (-660 3210);
FORCEPROP 0 LASTPIN (-650 3150) $PN AD77
J 2
(-660 3160);
DISPLAY 0.680851 (-660 3160);
PAINT MONO (-660 3160);
FORCEPROP 0 LASTPIN (1750 3750) $PN AV65
J 0
(1760 3760);
DISPLAY 0.680851 (1760 3760);
PAINT MONO (1760 3760);
FORCEPROP 0 LASTPIN (1750 3000) $PN AY24
J 0
(1760 3010);
DISPLAY 0.680851 (1760 3010);
PAINT MONO (1760 3010);
FORCEPROP 0 LASTPIN (1750 2800) $PN BA25
J 0
(1760 2810);
DISPLAY 0.680851 (1760 2810);
PAINT MONO (1760 2810);
FORCEPROP 0 LASTPIN (1750 3600) $PN BD71
J 0
(1760 3610);
DISPLAY 0.680851 (1760 3610);
PAINT MONO (1760 3610);
FORCEPROP 0 LASTPIN (1750 2250) $PN BE21
J 0
(1760 2260);
DISPLAY 0.680851 (1760 2260);
PAINT MONO (1760 2260);
FORCEPROP 0 LASTPIN (1750 3650) $PN BF71
J 0
(1760 3660);
DISPLAY 0.680851 (1760 3660);
PAINT MONO (1760 3660);
FORCEPROP 0 LASTPIN (-650 3050) $PN BG78
J 2
(-660 3060);
DISPLAY 0.680851 (-660 3060);
PAINT MONO (-660 3060);
FORCEPROP 0 LASTPIN (1750 3850) $PN BJ21
J 0
(1760 3860);
DISPLAY 0.680851 (1760 3860);
PAINT MONO (1760 3860);
FORCEPROP 0 LASTPIN (1750 3900) $PN BK22
J 0
(1760 3910);
DISPLAY 0.680851 (1760 3910);
PAINT MONO (1760 3910);
FORCEPROP 0 LASTPIN (-650 3000) $PN BL60
J 2
(-660 3010);
DISPLAY 0.680851 (-660 3010);
PAINT MONO (-660 3010);
FORCEPROP 0 LASTPIN (1750 2950) $PN BM65
J 0
(1760 2960);
DISPLAY 0.680851 (1760 2960);
PAINT MONO (1760 2960);
FORCEPROP 0 LASTPIN (1750 4000) $PN BP22
J 0
(1760 4010);
DISPLAY 0.680851 (1760 4010);
PAINT MONO (1760 4010);
FORCEPROP 0 LASTPIN (1750 2750) $PN BP65
J 0
(1760 2760);
DISPLAY 0.680851 (1760 2760);
PAINT MONO (1760 2760);
FORCEPROP 0 LASTPIN (1750 3950) $PN BR21
J 0
(1760 3960);
DISPLAY 0.680851 (1760 3960);
PAINT MONO (1760 3960);
FORCEPROP 0 LASTPIN (1750 3700) $PN CC66
J 0
(1760 3710);
DISPLAY 0.680851 (1760 3710);
PAINT MONO (1760 3710);
FORCEPROP 0 LASTPIN (1750 3350) $PN CD22
J 0
(1760 3360);
DISPLAY 0.680851 (1760 3360);
PAINT MONO (1760 3360);
FORCEPROP 0 LASTPIN (1750 3500) $PN CD26
J 0
(1760 3510);
DISPLAY 0.680851 (1760 3510);
PAINT MONO (1760 3510);
FORCEPROP 0 LASTPIN (1750 3450) $PN CD30
J 0
(1760 3460);
DISPLAY 0.680851 (1760 3460);
PAINT MONO (1760 3460);
FORCEPROP 0 LASTPIN (1750 3400) $PN CF22
J 0
(1760 3410);
DISPLAY 0.680851 (1760 3410);
PAINT MONO (1760 3410);
FORCEPROP 0 LASTPIN (1750 3200) $PN CH69
J 0
(1760 3210);
DISPLAY 0.680851 (1760 3210);
PAINT MONO (1760 3210);
FORCEPROP 0 LASTPIN (1750 3150) $PN CJ68
J 0
(1760 3160);
DISPLAY 0.680851 (1760 3160);
PAINT MONO (1760 3160);
FORCEPROP 0 LASTPIN (1750 3250) $PN CJ70
J 0
(1760 3260);
DISPLAY 0.680851 (1760 3260);
PAINT MONO (1760 3260);
FORCEPROP 0 LASTPIN (1750 3100) $PN CK67
J 0
(1760 3110);
DISPLAY 0.680851 (1760 3110);
PAINT MONO (1760 3110);
FORCEPROP 0 LASTPIN (1750 2700) $PN CR25
J 0
(1760 2710);
DISPLAY 0.680851 (1760 2710);
PAINT MONO (1760 2710);
FORCEPROP 0 LASTPIN (1750 2900) $PN CT26
J 0
(1760 2910);
DISPLAY 0.680851 (1760 2910);
PAINT MONO (1760 2910);
FORCEPROP 0 LASTPIN (-650 3300) $PN CW41
J 2
(-660 3310);
DISPLAY 0.680851 (-660 3310);
PAINT MONO (-660 3310);
FORCEPROP 0 LASTPIN (1750 2850) $PN CW58
J 0
(1760 2860);
DISPLAY 0.680851 (1760 2860);
PAINT MONO (1760 2860);
FORCEPROP 0 LASTPIN (1750 2650) $PN CY57
J 0
(1760 2660);
DISPLAY 0.680851 (1760 2660);
PAINT MONO (1760 2660);
FORCEPROP 0 LASTPIN (-650 3450) $PN EG17
J 2
(-660 3460);
DISPLAY 0.680851 (-660 3460);
PAINT MONO (-660 3460);
FORCEPROP 0 LASTPIN (-650 3500) $PN U17
J 2
(-660 3510);
DISPLAY 0.680851 (-660 3510);
PAINT MONO (-660 3510);
FORCEPROP 0 LASTPIN (-650 3350) $PN W17
J 2
(-660 3360);
DISPLAY 0.680851 (-660 3360);
PAINT MONO (-660 3360);
FORCEPROP 2 LAST CDS_LIB pure_quanta
J 0
(550 3125);
DISPLAY INVISIBLE (550 3125);
FORCEPROP 1 LAST NEEDS_NO_SIZE TRUE
J 0
(550 3125);
DISPLAY 0.723404 (550 3125);
PAINT GREEN (550 3125);
DISPLAY INVISIBLE (550 3125);
FORCEPROP 1 LAST CDS_LMAN_SYM_OUTLINE -1050,1050,1050,-1000
J 0
(550 3125);
DISPLAY 0.468085 (550 3125);
PAINT GREEN (550 3125);
DISPLAY INVISIBLE (550 3125);
FORCEPROP 2 LAST CDS_LOCATION U1
J 0
(-500 4500);
DISPLAY 1.021277 (-500 4500);
DISPLAY INVISIBLE (-500 4500);
FORCEPROP 0 LAST $SEC 5
J 0
(-500 4500);
DISPLAY 0.680851 (-500 4500);
PAINT MONO (-500 4500);
DISPLAY INVISIBLE (-500 4500);
FORCEPROP 2 LAST CDS_SEC 5
J 0
(-500 4500);
DISPLAY 1.021277 (-500 4500);
DISPLAY INVISIBLE (-500 4500);
FORCEPROP 1 LAST PATH I1
J 0
(550 3125);
DISPLAY 0.723404 (550 3125);
PAINT GREEN (550 3125);
DISPLAY INVISIBLE (550 3125);
FORCEADD QUANTA_TITLE_BLOCK_C..1
(5175 -1525);
FORCEPROP 0 LAST CDS_CON_LAST_MODIFIED Fri Aug 25 14:00:31 2023
J 0
(3290 -1510);
PAINT MONO (3290 -1510);
DISPLAY INVISIBLE (3290 -1510);
FORCEPROP 2 LAST CUSTOM_TXT_CDS <XR_PAGE_TITLE>
J 0
(-2715 3725);
DISPLAY 0.638298 (-2715 3725);
PAINT PINK (-2715 3725);
DISPLAY INVISIBLE (-2715 3725);
FORCEPROP 2 LAST CUSTOM_TXT_CDS <CON_PAGE_NUM> OF <CON_TOTAL_PAGES>
J 0
(4729 -1507);
DISPLAY 0.978723 (4729 -1507);
FORCEPROP 2 LAST CUSTOM_TXT_CDS <Q_REV>
J 0
(4991 -1422);
DISPLAY 1.212766 (4991 -1422);
FORCEPROP 2 LAST CUSTOM_TXT_CDS <Q_NUMBER>
J 0
(3772 -1422);
DISPLAY 1.212766 (3772 -1422);
FORCEPROP 2 LAST CUSTOM_TXT_CDS <Q_PROJ>
J 0
(2793 -1423);
DISPLAY 1.212766 (2793 -1423);
FORCEPROP 2 LAST CUSTOM_TXT_CDS <CON_LAST_MODIFIED>
J 0
(3290 -1510);
DISPLAY 0.978723 (3290 -1510);
FORCEPROP 1 LAST CUSTOM_TXT_CDS <NAME_2>
J 0
(2000 -1475);
FORCEPROP 1 LAST CUSTOM_TXT_CDS <NAME_1>
J 0
(2000 -1350);
FORCEPROP 1 LAST Q_TITLE SPR CPU1 MISC:VIEW MDFI/HBM(5 OF 30)
J 0
(-4191 -1499);
DISPLAY 1.957447 (-4191 -1499);
PAINT GREEN (-4191 -1499);
FORCEPROP 1 LAST Q_DEPT 
J 1
(1412 -1476);
DISPLAY 1.957447 (1412 -1476);
PAINT GREEN (1412 -1476);
FORCEPROP 2 LAST CDS_LIB pure_quanta
J 0
(5175 -1525);
PAINT MONO (5175 -1525);
DISPLAY INVISIBLE (5175 -1525);
FORCEPROP 1 LAST CDS_LMAN_SYM_OUTLINE -9475,6775,100,-125
J 0
(5175 -1525);
DISPLAY 0.468085 (5175 -1525);
PAINT GREEN (5175 -1525);
DISPLAY INVISIBLE (5175 -1525);
FORCEPROP 2 LAST PAGE_BORDER TRUE
J 0
(-2715 3725);
DISPLAY 0.638298 (-2715 3725);
PAINT PINK (-2715 3725);
DISPLAY INVISIBLE (-2715 3725);
FORCEPROP 2 LAST CDS_XR_PAGE_TITLE CR-48 : @S9S_MB_2U_LIB.S9S_MB_2U(SCH_1):PAGE48
J 0
(-2715 3725);
DISPLAY 0.638298 (-2715 3725);
PAINT PINK (-2715 3725);
DISPLAY INVISIBLE (-2715 3725);
FORCEPROP 1 LAST COMMENT_BODY TRUE
J 0
(5187 -1538);
DISPLAY 0.978723 (5187 -1538);
PAINT GREEN (5187 -1538);
DISPLAY INVISIBLE (5187 -1538);
WIRE 16 -1 (-2325 3450)(-650 3450);
FORCEPROP 2 LAST SIG_NAME NC_CPU1_HBM0_VIEWDIG1
J 0
(-2262 3459);
DISPLAY 0.680851 (-2262 3459);
PAINT WHITE (-2262 3459);
WIRE 16 -1 (-650 3350)(-2325 3350);
FORCEPROP 2 LAST SIG_NAME NC_CPU1_HBM1_VIEWDIG0
J 0
(-2262 3359);
DISPLAY 0.680851 (-2262 3359);
PAINT WHITE (-2262 3359);
WIRE 16 -1 (-2325 3300)(-650 3300);
FORCEPROP 2 LAST SIG_NAME NC_CPU1_HBM1_VIEWDIG1
J 0
(-2262 3309);
DISPLAY 0.680851 (-2262 3309);
PAINT WHITE (-2262 3309);
WIRE 16 -1 (-650 3200)(-2325 3200);
FORCEPROP 2 LAST SIG_NAME NC_CPU1_HBM2_VIEWDIG0
J 0
(-2262 3209);
DISPLAY 0.680851 (-2262 3209);
PAINT WHITE (-2262 3209);
WIRE 16 -1 (-2325 3150)(-650 3150);
FORCEPROP 2 LAST SIG_NAME NC_CPU1_HBM2_VIEWDIG1
J 0
(-2262 3159);
DISPLAY 0.680851 (-2262 3159);
PAINT WHITE (-2262 3159);
WIRE 16 -1 (3425 3150)(1750 3150);
FORCEPROP 2 LAST SIG_NAME NC_CPU1_MDFI_DIE11_NS0
J 0
(2009 3159);
DISPLAY 0.680851 (2009 3159);
PAINT WHITE (2009 3159);
WIRE 16 -1 (3425 3250)(1750 3250);
FORCEPROP 2 LAST SIG_NAME NC_CPU1_MDFI_DIE11_EW0
J 0
(2009 3259);
DISPLAY 0.680851 (2009 3259);
PAINT WHITE (2009 3259);
WIRE 16 -1 (3425 3100)(1750 3100);
FORCEPROP 2 LAST SIG_NAME NC_CPU1_MDFI_DIE11_NS1
J 0
(2009 3109);
DISPLAY 0.680851 (2009 3109);
PAINT WHITE (2009 3109);
WIRE 16 -1 (3425 2700)(1750 2700);
FORCEPROP 2 LAST SIG_NAME NC_CPU1_VIEWPIN_GNR2
J 0
(2009 2709);
DISPLAY 0.680851 (2009 2709);
PAINT WHITE (2009 2709);
WIRE 16 -1 (3425 2900)(1750 2900);
FORCEPROP 2 LAST SIG_NAME NC_CPU1_VIEWPIN_GNR0
J 0
(2009 2909);
DISPLAY 0.680851 (2009 2909);
PAINT WHITE (2009 2909);
WIRE 16 -1 (3425 2850)(1750 2850);
FORCEPROP 2 LAST SIG_NAME NC_CPU1_VIEWPIN_GNR1
J 0
(2009 2859);
DISPLAY 0.680851 (2009 2859);
PAINT WHITE (2009 2859);
WIRE 16 -1 (3425 2650)(1750 2650);
FORCEPROP 2 LAST SIG_NAME NC_CPU1_VIEWPIN_GNR3
J 0
(2009 2659);
DISPLAY 0.680851 (2009 2659);
PAINT WHITE (2009 2659);
WIRE 16 -1 (-650 3500)(-2325 3500);
FORCEPROP 2 LAST SIG_NAME NC_CPU1_HBM0_VIEWDIG0
J 0
(-2262 3509);
DISPLAY 0.680851 (-2262 3509);
PAINT WHITE (-2262 3509);
WIRE 16 -1 (3425 3750)(1750 3750);
FORCEPROP 2 LAST SIG_NAME NC_CPU1_MDFI_DIE01_EW0
J 0
(2009 3759);
DISPLAY 0.680851 (2009 3759);
PAINT WHITE (2009 3759);
WIRE 16 -1 (3425 3000)(1750 3000);
FORCEPROP 2 LAST SIG_NAME NC_CPU1_SOC_SPARE0
J 0
(2009 3009);
DISPLAY 0.680851 (2009 3009);
PAINT WHITE (2009 3009);
WIRE 16 -1 (3425 2800)(1750 2800);
FORCEPROP 2 LAST SIG_NAME NC_CPU1_SOC_SPARE4
J 0
(2009 2809);
DISPLAY 0.680851 (2009 2809);
PAINT WHITE (2009 2809);
WIRE 16 -1 (3425 3600)(1750 3600);
FORCEPROP 2 LAST SIG_NAME NC_CPU1_MDFI_DIE01_NS1
J 0
(2009 3609);
DISPLAY 0.680851 (2009 3609);
PAINT WHITE (2009 3609);
WIRE 16 -1 (3425 2250)(1750 2250);
FORCEPROP 2 LAST SIG_NAME TP_CPU1_DIE_HVM_EN_LVC1
J 0
(2009 2259);
DISPLAY 0.680851 (2009 2259);
PAINT WHITE (2009 2259);
WIRE 16 -1 (3425 3650)(1750 3650);
FORCEPROP 2 LAST SIG_NAME NC_CPU1_MDFI_DIE01_NS0
J 0
(2009 3659);
DISPLAY 0.680851 (2009 3659);
PAINT WHITE (2009 3659);
WIRE 16 -1 (-650 3050)(-2325 3050);
FORCEPROP 2 LAST SIG_NAME NC_CPU1_HBM3_VIEWDIG0
J 0
(-2262 3059);
DISPLAY 0.680851 (-2262 3059);
PAINT WHITE (-2262 3059);
WIRE 16 -1 (3425 3850)(1750 3850);
FORCEPROP 2 LAST SIG_NAME NC_CPU1_MDFI_DIE00_NS1
J 0
(2009 3859);
DISPLAY 0.680851 (2009 3859);
PAINT WHITE (2009 3859);
WIRE 16 -1 (3425 3900)(1750 3900);
FORCEPROP 2 LAST SIG_NAME NC_CPU1_MDFI_DIE00_NS0
J 0
(2009 3909);
DISPLAY 0.680851 (2009 3909);
PAINT WHITE (2009 3909);
WIRE 16 -1 (-2325 3000)(-650 3000);
FORCEPROP 2 LAST SIG_NAME NC_CPU1_HBM3_VIEWDIG1
J 0
(-2262 3009);
DISPLAY 0.680851 (-2262 3009);
PAINT WHITE (-2262 3009);
WIRE 16 -1 (3425 2950)(1750 2950);
FORCEPROP 2 LAST SIG_NAME NC_CPU1_SOC_SPARE1
J 0
(2009 2959);
DISPLAY 0.680851 (2009 2959);
PAINT WHITE (2009 2959);
WIRE 16 -1 (3425 4000)(1750 4000);
FORCEPROP 2 LAST SIG_NAME NC_CPU1_MDFI_DIE00_EW0
J 0
(2009 4009);
DISPLAY 0.680851 (2009 4009);
PAINT WHITE (2009 4009);
WIRE 16 -1 (3425 2750)(1750 2750);
FORCEPROP 2 LAST SIG_NAME NC_CPU1_SOC_SPARE5
J 0
(2009 2759);
DISPLAY 0.680851 (2009 2759);
PAINT WHITE (2009 2759);
WIRE 16 -1 (3425 3950)(1750 3950);
FORCEPROP 2 LAST SIG_NAME NC_CPU1_MDFI_DIE00_EW1
J 0
(2009 3959);
DISPLAY 0.680851 (2009 3959);
PAINT WHITE (2009 3959);
WIRE 16 -1 (3425 3700)(1750 3700);
FORCEPROP 2 LAST SIG_NAME NC_CPU1_MDFI_DIE01_EW1
J 0
(2009 3709);
DISPLAY 0.680851 (2009 3709);
PAINT WHITE (2009 3709);
WIRE 16 -1 (3425 3350)(1750 3350);
FORCEPROP 2 LAST SIG_NAME NC_CPU1_MDFI_DIE10_NS1
J 0
(2009 3359);
DISPLAY 0.680851 (2009 3359);
PAINT WHITE (2009 3359);
WIRE 16 -1 (3425 3500)(1750 3500);
FORCEPROP 2 LAST SIG_NAME NC_CPU1_MDFI_DIE10_EW0
J 0
(2009 3509);
DISPLAY 0.680851 (2009 3509);
PAINT WHITE (2009 3509);
WIRE 16 -1 (3425 3450)(1750 3450);
FORCEPROP 2 LAST SIG_NAME NC_CPU1_MDFI_DIE10_EW1
J 0
(2009 3459);
DISPLAY 0.680851 (2009 3459);
PAINT WHITE (2009 3459);
WIRE 16 -1 (3425 3400)(1750 3400);
FORCEPROP 2 LAST SIG_NAME NC_CPU1_MDFI_DIE10_NS0
J 0
(2009 3409);
DISPLAY 0.680851 (2009 3409);
PAINT WHITE (2009 3409);
WIRE 16 -1 (3425 3200)(1750 3200);
FORCEPROP 2 LAST SIG_NAME NC_CPU1_MDFI_DIE11_EW1
J 0
(2009 3209);
DISPLAY 0.680851 (2009 3209);
PAINT WHITE (2009 3209);
QUIT
